(kicad_pcb
	(version 20260206)
	(generator "pcbnew")
	(generator_version "10.0")
	(general
		(thickness 1.6)
		(legacy_teardrops no)
	)
	(paper "A4")
	(title_block
		(title "01162023_DA0F0TEBIF0_F0T_Expander_BD_F_brd_V02_OCP.brd")
		(comment 1 "Grand Teton / footprints 7745-7750 of 9728")
	)
	(layers
		(0 "F.Cu" signal "TOP")
		(4 "In1.Cu" signal "GND")
		(6 "In2.Cu" signal "VCC")
		(8 "In3.Cu" signal "VCC1")
		(10 "In4.Cu" signal "GND1")
		(12 "In5.Cu" signal "IN1")
		(14 "In6.Cu" signal "GND2")
		(16 "In7.Cu" signal "IN2")
		(18 "In8.Cu" signal "GND3")
		(20 "In9.Cu" signal "IN3")
		(22 "In10.Cu" signal "GND4")
		(24 "In11.Cu" signal "IN4")
		(26 "In12.Cu" signal "GND5")
		(28 "In13.Cu" signal "IN5")
		(30 "In14.Cu" signal "GND6")
		(32 "In15.Cu" signal "IN6")
		(34 "In16.Cu" signal "GND7")
		(2 "B.Cu" signal "BOTTOM")
		(9 "F.Adhes" user "F.Adhesive")
		(11 "B.Adhes" user "B.Adhesive")
		(13 "F.Paste" user "Package Geometry/Pastemask Top")
		(15 "B.Paste" user "Package Geometry/Pastemask Bottom")
		(5 "F.SilkS" user "Ref Des/Silkscreen Top")
		(7 "B.SilkS" user "Ref Des/Silkscreen Bottom")
		(1 "F.Mask" user "Board Geometry/Soldermask Top")
		(3 "B.Mask" user "Board Geometry/Soldermask Bottom")
		(17 "Dwgs.User" user "User.Drawings")
		(19 "Cmts.User" user "User.Comments")
		(21 "Eco1.User" user "User.Eco1")
		(23 "Eco2.User" user "User.Eco2")
		(25 "Edge.Cuts" user "Board Geometry/Outline")
		(27 "Margin" user)
		(31 "F.CrtYd" user "Package Geometry/Place Bound Top")
		(29 "B.CrtYd" user "Package Geometry/Place Bound Bottom")
		(35 "F.Fab" user "Ref Des/Assembly Top")
		(33 "B.Fab" user "Ref Des/Assembly Bottom")
	)
	(footprint ""
		(layer "B.Cu")
		(at 56.200802 -161.074862 -90)
		(property "Reference" "R50"
			(at 0 0 90)
			(layer "B.SilkS")
			(hide yes)
			(effects
				(font
					(size 1.27 1.27)
				)
				(justify mirror)
			)
		)
		(property "Value" ""
			(at 0 0 90)
			(layer "B.Fab")
			(effects
				(font
					(size 1.27 1.27)
				)
				(justify mirror)
			)
		)
		(duplicate_pad_numbers_are_jumpers no)
		(fp_line
			(start -0.7874 0.4064)
			(end 0.7874 0.4064)
			(stroke
				(width 0.1524)
				(type default)
			)
			(layer "B.SilkS")
		)
		(fp_line
			(start 0.7874 0.4064)
			(end 0.7874 -0.4064)
			(stroke
				(width 0.1524)
				(type default)
			)
			(layer "B.SilkS")
		)
		(fp_line
			(start -0.7874 -0.4064)
			(end -0.7874 0.4064)
			(stroke
				(width 0.1524)
				(type default)
			)
			(layer "B.SilkS")
		)
		(fp_line
			(start 0.7874 -0.4064)
			(end -0.7874 -0.4064)
			(stroke
				(width 0.1524)
				(type default)
			)
			(layer "B.SilkS")
		)
		(fp_line
			(start -0.67945 0.3048)
			(end -0.120396 0.3048)
			(stroke
				(width 0.1)
				(type default)
			)
			(layer "B.Fab")
		)
		(fp_line
			(start -0.120396 0.3048)
			(end -0.120396 0.2794)
			(stroke
				(width 0.1)
				(type default)
			)
			(layer "B.Fab")
		)
		(fp_line
			(start 0.12065 0.3048)
			(end 0.67945 0.3048)
			(stroke
				(width 0.1)
				(type default)
			)
			(layer "B.Fab")
		)
		(fp_line
			(start 0.67945 0.3048)
			(end 0.67945 -0.305054)
			(stroke
				(width 0.1)
				(type default)
			)
			(layer "B.Fab")
		)
		(fp_line
			(start -0.120396 0.2794)
			(end 0.12065 0.2794)
			(stroke
				(width 0.1)
				(type default)
			)
			(layer "B.Fab")
		)
		(fp_line
			(start 0.12065 0.2794)
			(end 0.12065 0.3048)
			(stroke
				(width 0.1)
				(type default)
			)
			(layer "B.Fab")
		)
		(fp_line
			(start -0.12065 -0.2794)
			(end -0.12065 -0.3048)
			(stroke
				(width 0.1)
				(type default)
			)
			(layer "B.Fab")
		)
		(fp_line
			(start 0.12065 -0.2794)
			(end -0.12065 -0.2794)
			(stroke
				(width 0.1)
				(type default)
			)
			(layer "B.Fab")
		)
		(fp_line
			(start -0.67945 -0.3048)
			(end -0.67945 0.3048)
			(stroke
				(width 0.1)
				(type default)
			)
			(layer "B.Fab")
		)
		(fp_line
			(start -0.12065 -0.3048)
			(end -0.67945 -0.3048)
			(stroke
				(width 0.1)
				(type default)
			)
			(layer "B.Fab")
		)
		(fp_line
			(start 0.12065 -0.305054)
			(end 0.12065 -0.2794)
			(stroke
				(width 0.1)
				(type default)
			)
			(layer "B.Fab")
		)
		(fp_line
			(start 0.67945 -0.305054)
			(end 0.12065 -0.305054)
			(stroke
				(width 0.1)
				(type default)
			)
			(layer "B.Fab")
		)
		(pad "1" smd circle
			(at 0.40005 0 90)
			(size 0 0)
			(layers "B.Cu" "B.Mask" "B.Paste")
			(net "P3V3_AUX")
		)
		(pad "2" smd circle
			(at -0.40005 0 90)
			(size 0 0)
			(layers "B.Cu" "B.Mask" "B.Paste")
			(net "HP_NIC0_HSC_PWRGD_N")
		)
	)
	(footprint ""
		(layer "B.Cu")
		(at 285.619952 -305.399948 -90)
		(property "Reference" "C3325"
			(at 0 0 90)
			(layer "B.SilkS")
			(hide yes)
			(effects
				(font
					(size 1.27 1.27)
				)
				(justify mirror)
			)
		)
		(property "Value" ""
			(at 0 0 90)
			(layer "B.Fab")
			(effects
				(font
					(size 1.27 1.27)
				)
				(justify mirror)
			)
		)
		(duplicate_pad_numbers_are_jumpers no)
		(fp_line
			(start -0.299974 0.150114)
			(end 0.299974 0.150114)
			(stroke
				(width 0.1)
				(type default)
			)
			(layer "B.Fab")
		)
		(fp_line
			(start 0.299974 0.150114)
			(end 0.299974 -0.150114)
			(stroke
				(width 0.1)
				(type default)
			)
			(layer "B.Fab")
		)
		(fp_line
			(start -0.299974 -0.150114)
			(end -0.299974 0.150114)
			(stroke
				(width 0.1)
				(type default)
			)
			(layer "B.Fab")
		)
		(fp_line
			(start 0.299974 -0.150114)
			(end -0.299974 -0.150114)
			(stroke
				(width 0.1)
				(type default)
			)
			(layer "B.Fab")
		)
		(pad "1" smd rect
			(at 0.2667 0 90)
			(size 0.3048 0.381)
			(layers "B.Cu" "B.Mask" "B.Paste")
			(net "P1V25_SERDES_VDDPLL_PEX2")
		)
		(pad "2" smd rect
			(at -0.2667 0 90)
			(size 0.3048 0.381)
			(layers "B.Cu" "B.Mask" "B.Paste")
			(net "GND")
		)
	)
	(footprint ""
		(layer "B.Cu")
		(at 131.075176 -221.640908 90)
		(property "Reference" "R3465"
			(at 0 0 90)
			(layer "B.SilkS")
			(hide yes)
			(effects
				(font
					(size 1.27 1.27)
				)
				(justify mirror)
			)
		)
		(property "Value" ""
			(at 0 0 90)
			(layer "B.Fab")
			(effects
				(font
					(size 1.27 1.27)
				)
				(justify mirror)
			)
		)
		(duplicate_pad_numbers_are_jumpers no)
		(fp_line
			(start 0.7874 -0.4064)
			(end -0.7874 -0.4064)
			(stroke
				(width 0.1524)
				(type default)
			)
			(layer "B.SilkS")
		)
		(fp_line
			(start -0.7874 -0.4064)
			(end -0.7874 0.4064)
			(stroke
				(width 0.1524)
				(type default)
			)
			(layer "B.SilkS")
		)
		(fp_line
			(start 0.7874 0.4064)
			(end 0.7874 -0.4064)
			(stroke
				(width 0.1524)
				(type default)
			)
			(layer "B.SilkS")
		)
		(fp_line
			(start -0.7874 0.4064)
			(end 0.7874 0.4064)
			(stroke
				(width 0.1524)
				(type default)
			)
			(layer "B.SilkS")
		)
		(fp_line
			(start 0.67945 -0.305054)
			(end 0.12065 -0.305054)
			(stroke
				(width 0.1)
				(type default)
			)
			(layer "B.Fab")
		)
		(fp_line
			(start 0.12065 -0.305054)
			(end 0.12065 -0.2794)
			(stroke
				(width 0.1)
				(type default)
			)
			(layer "B.Fab")
		)
		(fp_line
			(start -0.12065 -0.3048)
			(end -0.67945 -0.3048)
			(stroke
				(width 0.1)
				(type default)
			)
			(layer "B.Fab")
		)
		(fp_line
			(start -0.67945 -0.3048)
			(end -0.67945 0.3048)
			(stroke
				(width 0.1)
				(type default)
			)
			(layer "B.Fab")
		)
		(fp_line
			(start 0.12065 -0.2794)
			(end -0.12065 -0.2794)
			(stroke
				(width 0.1)
				(type default)
			)
			(layer "B.Fab")
		)
		(fp_line
			(start -0.12065 -0.2794)
			(end -0.12065 -0.3048)
			(stroke
				(width 0.1)
				(type default)
			)
			(layer "B.Fab")
		)
		(fp_line
			(start 0.12065 0.2794)
			(end 0.12065 0.3048)
			(stroke
				(width 0.1)
				(type default)
			)
			(layer "B.Fab")
		)
		(fp_line
			(start -0.120396 0.2794)
			(end 0.12065 0.2794)
			(stroke
				(width 0.1)
				(type default)
			)
			(layer "B.Fab")
		)
		(fp_line
			(start 0.67945 0.3048)
			(end 0.67945 -0.305054)
			(stroke
				(width 0.1)
				(type default)
			)
			(layer "B.Fab")
		)
		(fp_line
			(start 0.12065 0.3048)
			(end 0.67945 0.3048)
			(stroke
				(width 0.1)
				(type default)
			)
			(layer "B.Fab")
		)
		(fp_line
			(start -0.120396 0.3048)
			(end -0.120396 0.2794)
			(stroke
				(width 0.1)
				(type default)
			)
			(layer "B.Fab")
		)
		(fp_line
			(start -0.67945 0.3048)
			(end -0.120396 0.3048)
			(stroke
				(width 0.1)
				(type default)
			)
			(layer "B.Fab")
		)
		(pad "1" smd circle
			(at 0.40005 0 270)
			(size 0 0)
			(layers "B.Cu" "B.Mask" "B.Paste")
			(net "SPI_PEX1_CLK_MUX")
		)
		(pad "2" smd circle
			(at -0.40005 0 270)
			(size 0 0)
			(layers "B.Cu" "B.Mask" "B.Paste")
			(net "SPI_PEX1_CLK_MUX_R")
		)
	)
	(footprint ""
		(layer "B.Cu")
		(at 228.189536 -150.44293 90)
		(property "Reference" "C2804"
			(at 0 0 90)
			(layer "B.SilkS")
			(hide yes)
			(effects
				(font
					(size 1.27 1.27)
				)
				(justify mirror)
			)
		)
		(property "Value" ""
			(at 0 0 90)
			(layer "B.Fab")
			(effects
				(font
					(size 1.27 1.27)
				)
				(justify mirror)
			)
		)
		(duplicate_pad_numbers_are_jumpers no)
		(fp_line
			(start 0.7874 -0.4064)
			(end -0.7874 -0.4064)
			(stroke
				(width 0.1524)
				(type default)
			)
			(layer "B.SilkS")
		)
		(fp_line
			(start -0.7874 -0.4064)
			(end -0.7874 0.4064)
			(stroke
				(width 0.1524)
				(type default)
			)
			(layer "B.SilkS")
		)
		(fp_line
			(start 0.7874 0.4064)
			(end 0.7874 -0.4064)
			(stroke
				(width 0.1524)
				(type default)
			)
			(layer "B.SilkS")
		)
		(fp_line
			(start -0.7874 0.4064)
			(end 0.7874 0.4064)
			(stroke
				(width 0.1524)
				(type default)
			)
			(layer "B.SilkS")
		)
		(fp_line
			(start 0.67945 -0.305054)
			(end 0.12065 -0.305054)
			(stroke
				(width 0.1)
				(type default)
			)
			(layer "B.Fab")
		)
		(fp_line
			(start 0.12065 -0.305054)
			(end 0.12065 -0.2794)
			(stroke
				(width 0.1)
				(type default)
			)
			(layer "B.Fab")
		)
		(fp_line
			(start -0.12065 -0.3048)
			(end -0.67945 -0.3048)
			(stroke
				(width 0.1)
				(type default)
			)
			(layer "B.Fab")
		)
		(fp_line
			(start -0.67945 -0.3048)
			(end -0.67945 0.3048)
			(stroke
				(width 0.1)
				(type default)
			)
			(layer "B.Fab")
		)
		(fp_line
			(start 0.12065 -0.2794)
			(end -0.12065 -0.2794)
			(stroke
				(width 0.1)
				(type default)
			)
			(layer "B.Fab")
		)
		(fp_line
			(start -0.12065 -0.2794)
			(end -0.12065 -0.3048)
			(stroke
				(width 0.1)
				(type default)
			)
			(layer "B.Fab")
		)
		(fp_line
			(start 0.12065 0.2794)
			(end 0.12065 0.3048)
			(stroke
				(width 0.1)
				(type default)
			)
			(layer "B.Fab")
		)
		(fp_line
			(start -0.120396 0.2794)
			(end 0.12065 0.2794)
			(stroke
				(width 0.1)
				(type default)
			)
			(layer "B.Fab")
		)
		(fp_line
			(start 0.67945 0.3048)
			(end 0.67945 -0.305054)
			(stroke
				(width 0.1)
				(type default)
			)
			(layer "B.Fab")
		)
		(fp_line
			(start 0.12065 0.3048)
			(end 0.67945 0.3048)
			(stroke
				(width 0.1)
				(type default)
			)
			(layer "B.Fab")
		)
		(fp_line
			(start -0.120396 0.3048)
			(end -0.120396 0.2794)
			(stroke
				(width 0.1)
				(type default)
			)
			(layer "B.Fab")
		)
		(fp_line
			(start -0.67945 0.3048)
			(end -0.120396 0.3048)
			(stroke
				(width 0.1)
				(type default)
			)
			(layer "B.Fab")
		)
		(pad "1" smd circle
			(at 0.40005 0 270)
			(size 0 0)
			(layers "B.Cu" "B.Mask" "B.Paste")
			(net "P3V3_CLK_GEN_VDDMXCK_CK440_PEX")
		)
		(pad "2" smd circle
			(at -0.40005 0 270)
			(size 0 0)
			(layers "B.Cu" "B.Mask" "B.Paste")
			(net "GND")
		)
	)
	(footprint ""
		(layer "B.Cu")
		(at 162.4457 -296.37482)
		(property "Reference" "C3203"
			(at 0 0 0)
			(layer "B.SilkS")
			(hide yes)
			(effects
				(font
					(size 1.27 1.27)
				)
				(justify mirror)
			)
		)
		(property "Value" ""
			(at 0 0 0)
			(layer "B.Fab")
			(effects
				(font
					(size 1.27 1.27)
				)
				(justify mirror)
			)
		)
		(duplicate_pad_numbers_are_jumpers no)
		(fp_line
			(start -0.299974 -0.150114)
			(end -0.299974 0.150114)
			(stroke
				(width 0.1)
				(type default)
			)
			(layer "B.Fab")
		)
		(fp_line
			(start -0.299974 0.150114)
			(end 0.299974 0.150114)
			(stroke
				(width 0.1)
				(type default)
			)
			(layer "B.Fab")
		)
		(fp_line
			(start 0.299974 -0.150114)
			(end -0.299974 -0.150114)
			(stroke
				(width 0.1)
				(type default)
			)
			(layer "B.Fab")
		)
		(fp_line
			(start 0.299974 0.150114)
			(end 0.299974 -0.150114)
			(stroke
				(width 0.1)
				(type default)
			)
			(layer "B.Fab")
		)
		(pad "1" smd rect
			(at 0.2667 0 180)
			(size 0.3048 0.381)
			(layers "B.Cu" "B.Mask" "B.Paste")
			(net "PCEPLL2_VDDA18_PEX1")
		)
		(pad "2" smd rect
			(at -0.2667 0 180)
			(size 0.3048 0.381)
			(layers "B.Cu" "B.Mask" "B.Paste")
			(net "GND")
		)
	)
	(footprint ""
		(layer "B.Cu")
		(at 296.992802 -445.151764 180)
		(property "Reference" "X81"
			(at 0.1778 -1.92913 180)
			(unlocked yes)
			(layer "B.SilkS")
			(effects
				(font
					(size 0.7874 0.5842)
					(thickness 0.1524)
				)
				(justify left mirror)
			)
		)
		(property "Value" ""
			(at 0 0 0)
			(layer "B.Fab")
			(effects
				(font
					(size 1.27 1.27)
				)
				(justify mirror)
			)
		)
		(property "Device Type" "TP_TDR_4P_FTS_MPKT4_H025P0200_IO_TP15_TP_TDR_4P_DIP"
			(at -1.30175 1.27 90)
			(unlocked yes)
			(layer "B.Fab")
			(hide yes)
			(effects
				(font
					(size 0.635 0.4064)
					(thickness 0.1524)
				)
				(justify mirror)
			)
		)
		(property "User Part Number" "TP15"
			(at -1.30175 1.27 90)
			(unlocked yes)
			(layer "Cmts.User")
			(hide yes)
			(effects
				(font
					(size 0.635 0.4064)
					(thickness 0.1524)
				)
				(justify mirror)
			)
		)
		(duplicate_pad_numbers_are_jumpers no)
		(fp_line
			(start 0 3.81)
			(end -2.54 3.81)
			(stroke
				(width 0.1524)
				(type default)
			)
			(layer "B.SilkS")
		)
		(fp_line
			(start 0 3.175)
			(end 0 3.81)
			(stroke
				(width 0.1524)
				(type default)
			)
			(layer "B.SilkS")
		)
		(fp_line
			(start 0 0.635)
			(end 0 1.905)
			(stroke
				(width 0.1524)
				(type default)
			)
			(layer "B.SilkS")
		)
		(fp_line
			(start 0 -1.27)
			(end 0 -0.635)
			(stroke
				(width 0.1524)
				(type default)
			)
			(layer "B.SilkS")
		)
		(fp_line
			(start -2.54 3.81)
			(end -2.54 3.6703)
			(stroke
				(width 0.1524)
				(type default)
			)
			(layer "B.SilkS")
		)
		(fp_line
			(start -2.54 1.4097)
			(end -2.54 1.1303)
			(stroke
				(width 0.1524)
				(type default)
			)
			(layer "B.SilkS")
		)
		(fp_line
			(start -2.54 -1.1303)
			(end -2.54 -1.27)
			(stroke
				(width 0.1524)
				(type default)
			)
			(layer "B.SilkS")
		)
		(fp_line
			(start -2.54 -1.27)
			(end 0 -1.27)
			(stroke
				(width 0.1524)
				(type default)
			)
			(layer "B.SilkS")
		)
		(fp_poly
			(pts
				(xy 0.761746 0) (xy 2.285746 -0.762) (xy 2.285746 0.762)
			)
			(stroke
				(width 0)
				(type default)
			)
			(fill yes)
			(layer "B.SilkS")
		)
		(fp_line
			(start 0 3.81)
			(end -2.54 3.81)
			(stroke
				(width 0.1)
				(type default)
			)
			(layer "B.Fab")
		)
		(fp_line
			(start 0 -1.27)
			(end 0 3.81)
			(stroke
				(width 0.1)
				(type default)
			)
			(layer "B.Fab")
		)
		(fp_line
			(start -2.54 3.81)
			(end -2.54 -1.27)
			(stroke
				(width 0.1)
				(type default)
			)
			(layer "B.Fab")
		)
		(fp_line
			(start -2.54 -1.27)
			(end 0 -1.27)
			(stroke
				(width 0.1)
				(type default)
			)
			(layer "B.Fab")
		)
		(fp_poly
			(pts
				(xy 0.761746 0) (xy 2.285746 -0.762) (xy 2.285746 0.762)
			)
			(stroke
				(width 0)
				(type default)
			)
			(fill yes)
			(layer "B.Fab")
		)
		(pad "1" thru_hole circle
			(at 0 0)
			(size 1.0033 1.0033)
			(drill 0.249936)
			(layers "*.Cu" "*.Mask")
			(remove_unused_layers no)
			(net "TDR_DIFF_100_BOT_DIN")
			(clearance 0.10795)
			(padstack
				(mode front_inner_back)
				(layer "Inner"
					(shape circle)
					(size 0.8001 0.8001)
					(clearance 0.1524)
				)
				(layer "B.Cu"
					(shape circle)
					(size 1.0033 1.0033)
					(thermal_gap 0.10795)
					(clearance 0.10795)
				)
			)
		)
		(pad "2" thru_hole circle
			(at -2.54 0)
			(size 1.9939 1.9939)
			(drill 0.249936)
			(layers "*.Cu" "*.Mask")
			(remove_unused_layers no)
			(net "COUPON_GND1")
			(clearance 0.10795)
			(padstack
				(mode front_inner_back)
				(layer "Inner"
					(shape circle)
					(size 0.8001 0.8001)
					(clearance 0.1524)
				)
				(layer "B.Cu"
					(shape circle)
					(size 1.9939 1.9939)
					(thermal_gap 0.10795)
					(clearance 0.10795)
				)
			)
		)
		(pad "3" thru_hole circle
			(at -2.54 2.54)
			(size 1.9939 1.9939)
			(drill 0.249936)
			(layers "*.Cu" "*.Mask")
			(remove_unused_layers no)
			(net "COUPON_GND1")
			(clearance 0.10795)
			(padstack
				(mode front_inner_back)
				(layer "Inner"
					(shape circle)
					(size 0.8001 0.8001)
					(clearance 0.1524)
				)
				(layer "B.Cu"
					(shape circle)
					(size 1.9939 1.9939)
					(thermal_gap 0.10795)
					(clearance 0.10795)
				)
			)
		)
		(pad "4" thru_hole circle
			(at 0 2.54)
			(size 1.0033 1.0033)
			(drill 0.249936)
			(layers "*.Cu" "*.Mask")
			(remove_unused_layers no)
			(net "TDR_DIFF_100_BOT_DIP")
			(clearance 0.10795)
			(padstack
				(mode front_inner_back)
				(layer "Inner"
					(shape circle)
					(size 0.8001 0.8001)
					(clearance 0.1524)
				)
				(layer "B.Cu"
					(shape circle)
					(size 1.0033 1.0033)
					(thermal_gap 0.10795)
					(clearance 0.10795)
				)
			)
		)
	)
)
